******************************************************************************
 Bridge IC Runtime for Grand Teton Switch Board Release Note
******************************************************************************
BIC Runtime Version       : GT-SWB-2023.13.01
Release Date              : 2023/03/31
Platform                  : Grand Teton Switch Board
PLDM Image MD5 CheckSum      : 6205a5c923672ba3fd52f1742fec07f1
PLDM Image SHA256 CheckSum : babf15cb09b0b175a31f2d6adffb59a099fd47f3c9858dabe146514f90893c40
Bin Image MD5 Checksum: 1cf7f0a2745c1751c4833279fc0aa6b7
Bin Image SHA256 Checksum: ed79e446d526305febcd2f5112ecc61b31085bd5d5a9fa8e2f273078faa6032c

--------------------------------------------------
* [Feature]
- Support the feature of the system LED. #879
- Use the default value on those two HSCs. #890
- Change some sensors to DC access. #889
- Implement PLDM firmware update GetFirmwareParameters command #913
- Change PEX P1V8 PGA setting #966
- Modify SPI1 max frequency to 33.5 MHz #991
- Disabe HSC_UV_R_N (GPIOH0) internal pull down. #1006
- Modify LTC4286 power reading condition #1005
- Add stage define for PVT2 and MP #1004
- Support PLDM firmware update on all component (VR, CPLD, PEX, NIC) of SWB.

* [Fixed]
- [419428] - [F0T_PVT] Sensor ''SWB_PEX_P1V8_PWR_W'' show 0.00 Watts in BMC
- [405886] - [F0T_EVT2_B0 board] BIC fw version keep old or swb device fw show NA after update BIC fw under BMC
- [414470] - [F0TG EVT][ES2] Can not do GT_SWB_PEX_B0000502 error injection(update the wrong pex fw) with obmc v2022.52.2.

***************************** [NOTICE] ******************************************
The PLDM update implementation start from this version (2023.13.01) and should use the BMC firmware 
version starting from 2023.13.01 to use the package of PLDM to update firmware on the component of the SWB 
by the normal update process.

* [BIC update procedure]
 - Update SWB BIC from PLDM by BMC:
	$ fw-util swb --update bic gt_swb_ast1030_2023.13.01.pldm
 - Recovery SWB BIC by BMC:
	$ fw-util swb --update bic_recovery GT-SWB-2023.13.01.bin
 - Update the bin BIC image file by BMC
	$ fw-uitl swb --force --update bic GT-SWB-2023.13.01.bin

******************************************************************************
 Bridge IC Runtime for Grand Teton Switch Board Release Note
******************************************************************************
BIC Runtime Version       : GT-SWB-2023.05.01
Release Date              : 2023/01/30
Platform                  : Grand Teton Switch Board
Image MD5 CheckSum      : 7ea230efe0c9f4387b9695ab3c56d2e5

--------------------------------------------------
* [Feature]
- Support PVT stage revision ID.

* [Fixed]
- Modify get NIC firmware version during DC on pointer not free cause memory leak issue.
- Increase the message queue size to 0x20 of BMC via MCTP due to the NIC firmware update issue.
Note: Need to BMC stop NIC temperature sensor polling before updating NIC firmware, not supported in current BMC firmware 2022.52.01.

* [BIC update procedure]
 - Update SWB BIC by BMC:
	$ fw-util swb --update bic GT-SWB-2023.05.01.bin

******************************************************************************
 Bridge IC Runtime for Grand Teton Switch Board Release Note
******************************************************************************
BIC Runtime Version       : GT-SWB-2022.52.01
Release Date              : 2022/12/28
Platform                  : Grand Teton Switch Board
Image MD5 CheckSum      : d888fb89e8650048e3bafb0302ff1899

--------------------------------------------------
* [Feature]
- Since the latest firmware of PEX changed the version register, add a condition to check the register of the firmware version to read the PEX version.

* [Fixed]
- OpenBIC #768: Clear any other irq status when the bus recovery fail.
- OpenBIC #784: Add read after write and change slave handle.

* [BIC update procedure]
 - Update SWB BIC by BMC:
	$ fw-util swb --update bic GT-SWB-2022.52.01.bin


******************************************************************************
 Bridge IC Runtime for Grand Teton Switch Board Release Note
******************************************************************************
BIC Runtime Version       : GT-SWB-2022.50.01
Release Date              : 2022/12/15
Platform                  : Grand Teton Switch Board
Image MD5 CheckSum      : b73497c0d1d72715e4503d6062ebc409

--------------------------------------------------
* [Feature]
- Support PLDM command GetPLDMTypes and GetPLDMCommands.
- Handle the packages in the MCTP assembling function that missing the first start package with the same message tag.
- Modify the set/get GPIO effecter that checks GPIO configuration instead of GPIO get function.
- Decrease unnecessary buffer size use in the I2C target for MCTP use.

* [Fixed]
[410880] - [F0T_DVT_2nd MB] BMC lost to show usb0 device under BMC
Add a workaround to reset USB HUB when AC is on by BMC using the GPIO set effecter command, and change the way to check GPIO direction from this version to make sure the reset USB HUB pin is working.

* [BIC update procedure]
 - Update SWB BIC by BMC:
	$ fw-util swb --update bic GT-SWB-2022.50.01.bin

******************************************************************************
 Bridge IC Runtime for Grand Teton Switch Board Release Note
******************************************************************************
BIC Runtime Version       : GT-SWB-2022.49.01
Release Date              : 2022/12/08
Platform                  : Grand Teton Switch Board
Image MD5 CheckSum      : bc0110f06497141a0a9f78e378aa9836

--------------------------------------------------
* [Feature]
- Check NIC present then send MCTP send set endpoint command.
- Add MUTEX in EEPROM W/R function to ensure transmission integrity.
- Modify PEX temperature read function to ignore the zero value read from the register to avoid returning a meaningless high value.
- Modify the HSC related sensor accuracy for DVT board.
- Add MUTEX unlock in the IPMI i2c bridge command when access i2c mux failed.
- Add PEX initial retry when DC is on due to PEX may need some time to initial for the first time after the firmware update.
- Add a function to check data reading from the SMBUS to the MCTP to ensure data integrity.
- Support MPS VR (MP2971).

* [Fixed]
[410484] - [F0T_DVT][GT#D03] BMC alert ''SWB_PEXx_TEMP_C'' event log during run DC cycling test.
[410777] - [F0T_DVT][GT#D08] The sensor ''SWB_NICx'', ''SWB_PEXx'', ''SWB_OUTLET_TEMP'', ''SWB_E1S'', ''SWB_HSC'' and ''HMC_TEMP_GB'' show NA after run DC cycling test at loop 499.
[410854] - [F0T_DVT] BIC version show NA after do BIC FW update stress. (Note: BIC version 2022.47.1 <-> 2022.40.1)
[410239] - [F0TG_EVT_PR CPU][2nd][B0 SWB][QS][ES2] The pex fw was showed NA after updating pex fw via 1st AC cycle, then pex fw can showed the correct fw version after 2nd AC cycle.

* [BIC update procedure]
 - Update SWB BIC by BMC:
	$ fw-util swb --update bic GT-SWB-2022.49.01.bin


******************************************************************************
 Bridge IC Runtime for Grand Teton Switch Board Release Note
******************************************************************************
BIC Runtime Version       : GT-SWB-2022.47.01
Release Date              : 2022/11/22
Platform                  : Grand Teton Switch Board
Image MD5 CheckSum      : 69ff68f64ea42b78a07b0b6f60601fa6

--------------------------------------------------
* [Feature]
- Support PLDM effecter set/get command for GPIO.
- Add ADC sensor for reading different component sources (HSC, VR, ADC).

* [Fixed]
- Change the SPI frequency of PEX to 33 MHz.
- Change completion code of PEX firmware version read.

* [BIC update procedure]
 - Update SWB BIC by BMC:
	$ fw-util swb --update bic GT-SWB-2022.47.01.bin


******************************************************************************
 Bridge IC Runtime for Grand Teton Switch Board Release Note
******************************************************************************
BIC Runtime Version       : GT-SWB-2022.40.02
Release Date              : 2022/10/07
Platform                  : Grand Teton Switch Board
Image MD5 CheckSum      : f4ffde1d7920ca928b558574f8963047

--------------------------------------------------
* [Feature]
- Support DVT board with HSC LTC4286dot.


* [Fixed]
- Fixed pex89000 remove wrong node when get device type failed.
- Change reading PEX89000 version from flash register to SBR register.

* [BIC update procedure]
 - Update SWB BIC by BMC:
	$ fw-util swb --update bic GT-SWB-2022.40.02.bin

******************************************************************************
 Bridge IC Runtime for Grand Teton Switch Board Release Note
******************************************************************************
BIC Runtime Version       : GT-SWB-2022.40.01
Release Date              : 2022/10/03
Platform                  : Grand Teton Switch Board
Image MD5 CheckSum      : 2a67a0421887aabccbd6a60f1b5d5444

--------------------------------------------------
* [Feature]
- Support DVT board with different module.
- Due to DVT remove the i2c mux in front of the PCIe switch, add the PEX sensor table of DVT to support.
- Use revision id to distinguish the different stages and load the appropriate sensor table.
- Use ADC to distinguish different types of HSC, VR, and the power monitor IC.
- Change MPS5990 sensor reading accuracy formula.
- Add LTC4282 sensor reading accuracy formula.
- Change LTC4282 r_sense_mohm and ilim_adjust.
- Change power monitor IC i2c address of PEX P1V8 from 0x98 to 0x9A on DVT board.

* [Fixed]

* [BIC update procedure]
 - Update SWB BIC by BMC:
	$ fw-util swb --update bic GT-SWB-2022.40.01.bin


******************************************************************************
 Bridge IC Runtime for Grand Teton Switch Board Release Note
******************************************************************************
BIC Runtime Version       : GT-SWB-2022.37.01
Release Date              : 2022/09/13
Platform                  : Grand Teton Switch Board
Image MD5 CheckSum      : 88c2ac1b7ebdd9f08bafbcc1af9be8c1

--------------------------------------------------
* [Feature]
- Support switch board 2nd source FRU W/R on HSC module.
- Modify HSC MP5990 related configuration:
  1. Change the reading register of voltage and power to input.
  2. Adjust power reading value for accuracy by power team requirement.

* [Fixed]
- Fixed error parsing negative temperature sensor value.

* [BIC update procedure]
 - Update SWB BIC by BMC:
	$ fw-util swb --update bic GT-SWB-2022.37.01.bin

******************************************************************************
 Bridge IC Runtime for Grand Teton Switch Board Release Note
******************************************************************************
BIC Runtime Version       : GT-SWB-2022.33.01
Release Date              : 2022/08/19
Platform                  : Grand Teton Switch Board
Image MD5 CheckSum      : 37a8eccb1b8a7b8fc450c77610c26e39

--------------------------------------------------
* [Feature]
- EVT2 different configuration switch board support:
    1st  : ISL69259(VR) + MPS5990(HSC) + ISL28022(Power monitor IC)
    2nd  : XDPE12284(VR) + LTC4282(HSC) + INA230(Power monitor IC)
  Since the BOARD_ID pins were originally used to identify which configuration has no function in this stage, 
  so the current configuration is identified by IC_DEVICE_ID which gets from the VR chip. The way to identify 
  different configurations by BOARD_ID will be added back in the next stage (DVT).
- Check NIC and E1S sensor reading by present pin.
- Because the i2c bus of E1.S (BUS9) has two mux behind 16 E1.S with the same i2c address, so close all 
  mux channels after the sensor read to avoid conflict with other devices reading.

* [Fixed]
[400703] - [F0T_EVT] E1.S temp sesnor reading will dump to 0 when heat the E1.S drive via heatgun.
[401669] - [F0T_EVT] SWB PEX0~3 version show NA during DC cycle.
[403131] - [F0T_EVT] Some GT_SWB_E1S_x_TEMP_C sensor still keep value after unplug SSD from switch tray.

* [BIC update procedure]
 - Update SWB BIC by BMC:
	$ fw-util swb --update bic GT-SWB-2022.33.01.bin


******************************************************************************
 Bridge IC Runtime for Grand Teton Switch Board Release Note
******************************************************************************
BIC Runtime Version       : GT-SWB-2022.28.01
Release Date              : 2022/07/15
Platform                  : Grand Teton Switch Board
Image MD5 CheckSum      : c08468fa1d8e79a4dbfd6c88f9484dd5

--------------------------------------------------
* [Feature]
- Add shell command use in BIC console to stress E1.S power consumption on a given 
  device id in a 250 ms window with a sampling rate of 2 ms in a given duration.
  - Usage in BIC console:
    test e1s power [device index] [duration (minute)]
- Add PLDM platform sensor reading command
  - PLDM type:  0x02
  - Command id: 0x11

* [Fixed]

* [BIC update procedure]
 - Update SWB BIC by BMC:
	$ fw-util swb --update bic GT-SWB-2022.28.01.bin


******************************************************************************
 Bridge IC Runtime for Grand Teton Switch Board Release Note
******************************************************************************
BIC Runtime Version       : GT-SWB-2022.26.01
Release Date              : 2022/06/30
Platform                  : Grand Teton Switch Board
Image MD5 CheckSum      : 1205c96875a742bba96d359d2ead1c77

--------------------------------------------------
* [Feature]
- Add pex i2c mutex lock when read PEX version reading to avoid read incorrect data.
- Support all sensor read on switch board, but only can read when DC on from BMC (since BMC version 2022.26.1.TEST1).
  Reading switch board sensor command as below:
     $ sensor-util swb

* [Fixed]
- Fixed read incorrect pex version because not change i2c mux channel before access PEX.

* [BIC update procedure]
 - Update SWB BIC by BMC:
	$ fw-util swb --update bic GT-SWB-2022.26.01.bin

******************************************************************************
 Bridge IC Runtime for Grand Teton Switch Board Release Note
******************************************************************************
BIC Runtime Version       : GT-SWB-2022.25.01
Release Date              : 2022/06/21
Platform                  : Grand Teton Switch Board
Image Crc32 CheckSum      : e22878b8

--------------------------------------------------
* [Feature]
- Add mutex to protect reading in the PEX i2c bus to avoid reading incorrect data.
* [Fixed]
- Change check GPIO SYS_PWR_READY_N behavior to low active.

******************************************************************************
 Bridge IC Runtime for Grand Teton Switch Board Release Note
******************************************************************************
BIC Runtime Version       : GT-SWB-2022.24.01
Release Date              : 2022/06/17
Platform                  : Grand Teton Switch Board
Image Crc32 CheckSum      : bf21fa47

--------------------------------------------------
* [Feature]
- Add oem command to bridge i2c message by component id.(NetFn 0x38 command 0x74)

******************************************************************************
 Bridge IC Runtime for Grand Teton Switch Board Release Note
******************************************************************************
BIC Runtime Version       : GT-SWB-2022.22.1
Release Date              : 2022/06/02
Platform                  : Grand Teton Switch Board
Image Crc32 CheckSum      : 389c2af1

--------------------------------------------------
* [Feature]
- Add oem command to get component id (NetFn 0x38 command 0x0B)


******************************************************************************
 Bridge IC Runtime for Grand Teton Switch Board Release Note
******************************************************************************
BIC Runtime Version       : GT-SWB-2022.19.1
Release Date              : 2022/05/13
Platform                  : Grand Teton Switch Board
Image Crc32 CheckSum      : b43ac723

--------------------------------------------------
* [Feature]
- Change i2c bus index to 0-based by OpenBIC common code
- Support pcie switch firmware update 
  Note: 
      The firmware image should padding range from 0x000 to 0x400 before update.
      Firmware image start from 0x400.

******************************************************************************
 Bridge IC Runtime for Grand Teton Switch Board Release Note
******************************************************************************
BIC Runtime Version       : GT-SWB-2022.13.1
Release Date              : 2022/04/1
Platform                  : Grand Teton Switch Board
Image Crc32 CheckSum      : 99a4f72b

--------------------------------------------------
* [Feature]
- Add oem command read pcie switch flash (NetFn 0x38 command 0x72)
- Add oem command get FPGA user code (NetFn 0x38 command 0x73)
- Change IANA code to meta

******************************************************************************
 Bridge IC Runtime for Grand Teton Switch Board Release Note
******************************************************************************
BIC Runtime Version       : GT-SWB-2022.11.1
Release Date              : 2022/03/18
Platform                  : Grand Teton Switch Board
Image Crc32 CheckSum      : c2ceb832

--------------------------------------------------
* [Feature]
- MCTP over PLDM over IPMI command support
- Access SWB/FIO FRU by command
